# BASEBOARD_FAB2 (Tioga Pass) — schematic netlist excerpt (pin names and nets, part order shuffled) for the footprints in the layout excerpt that follows; sources: Cadence DE-HDL packaged netlist, KiCad conversion of Wiwynn_Tioga_Pass_MB.brd

R2T26  RES  200.0 1% CHIP  pkg 0402  page 93 : A = PVCCIO_CPU0 ; B = H_CPU_ERR1_GTL_R_N
R3T11  RES  49.9 1% CHIP  pkg 0402  page 215 : A = PVCCIO_CPU0 ; B = SVID_CLK1_CPU0_R

Q1L4  FET_N_DUAL  2N7002DW FET  pkg SMLF  page 168
  SOURCE(0)  = GND
  GATE(0)  = FM_DB_PRESENT
  DRAIN(0)  = TP_FET_Q56_3
  SOURCE(0)  = TP_FET_Q56_4
  GATE(0)  = TP_FET_Q56_4
  DRAIN(0)  = FM_POST_CARD_PRES_BMC_N

(kicad_pcb
	(version 20260206)
	(generator "pcbnew")
	(generator_version "10.0")
	(general
		(thickness 1.6)
		(legacy_teardrops no)
	)
	(paper "A4")
	(title_block
		(title "Wiwynn_Tioga_Pass_MB.brd")
		(comment 1 "Tioga Pass / footprints 4139-4141 of 4770")
	)
	(layers
		(0 "F.Cu" signal "TOP")
		(4 "In1.Cu" signal "L2GND")
		(6 "In2.Cu" signal "L3")
		(8 "In3.Cu" signal "L4GND")
		(10 "In4.Cu" signal "L5")
		(12 "In5.Cu" signal "L6GND")
		(14 "In6.Cu" signal "L7VCC")
		(16 "In7.Cu" signal "L8VCC")
		(18 "In8.Cu" signal "L9GND")
		(20 "In9.Cu" signal "L10")
		(22 "In10.Cu" signal "L11GND")
		(24 "In11.Cu" signal "L12")
		(26 "In12.Cu" signal "L13GND")
		(2 "B.Cu" signal "BOTTOM")
		(9 "F.Adhes" user "F.Adhesive")
		(11 "B.Adhes" user "B.Adhesive")
		(13 "F.Paste" user "Package Geometry/Pastemask Top")
		(15 "B.Paste" user "Package Geometry/Pastemask Bottom")
		(5 "F.SilkS" user "Ref Des/Silkscreen Top")
		(7 "B.SilkS" user "Ref Des/Silkscreen Bottom")
		(1 "F.Mask" user "Board Geometry/Soldermask Top")
		(3 "B.Mask" user "Board Geometry/Soldermask Bottom")
		(17 "Dwgs.User" user "User.Drawings")
		(19 "Cmts.User" user "User.Comments")
		(21 "Eco1.User" user "User.Eco1")
		(23 "Eco2.User" user "User.Eco2")
		(25 "Edge.Cuts" user "Board Geometry/Outline")
		(27 "Margin" user)
		(31 "F.CrtYd" user "Package Geometry/Place Bound Top")
		(29 "B.CrtYd" user "Package Geometry/Place Bound Bottom")
		(35 "F.Fab" user "Ref Des/Assembly Top")
		(33 "B.Fab" user "Ref Des/Assembly Bottom")
	)
	(footprint ""
		(layer "B.Cu")
		(at 373.884952 -43.224958)
		(property "Reference" "R2T26"
			(at 0 0 0)
			(layer "B.SilkS")
			(hide yes)
			(effects
				(font
					(size 1.27 1.27)
				)
				(justify mirror)
			)
		)
		(property "Value" ""
			(at 0 0 0)
			(layer "B.Fab")
			(effects
				(font
					(size 1.27 1.27)
				)
				(justify mirror)
			)
		)
		(duplicate_pad_numbers_are_jumpers no)
		(fp_poly
			(pts
				(xy 0.2794 -0.1016) (xy -0.2794 -0.1016) (xy -0.2794 0.9906) (xy 0.2794 0.9906)
			)
			(stroke
				(width 0)
				(type default)
			)
			(fill no)
			(layer "B.CrtYd")
		)
		(fp_line
			(start -0.2794 -0.1016)
			(end 0.2794 -0.1016)
			(stroke
				(width 0.1)
				(type default)
			)
			(layer "B.Fab")
		)
		(fp_line
			(start -0.2794 0.9906)
			(end -0.2794 -0.1016)
			(stroke
				(width 0.1)
				(type default)
			)
			(layer "B.Fab")
		)
		(fp_line
			(start 0.2794 -0.1016)
			(end 0.2794 0.9906)
			(stroke
				(width 0.1)
				(type default)
			)
			(layer "B.Fab")
		)
		(fp_line
			(start 0.2794 0.9906)
			(end -0.2794 0.9906)
			(stroke
				(width 0.1)
				(type default)
			)
			(layer "B.Fab")
		)
		(pad "1" smd rect
			(at 0 0 180)
			(size 0.508 0.508)
			(layers "B.Cu" "B.Mask" "B.Paste")
			(net "PVCCIO_CPU0")
		)
		(pad "2" smd rect
			(at 0 0.889 180)
			(size 0.508 0.508)
			(layers "B.Cu" "B.Mask" "B.Paste")
			(net "H_CPU_ERR1_GTL_R_N")
		)
		(zone
			(layer "B.Cu")
			(hatch none 0.5)
			(connect_pads
				(clearance 0)
			)
			(min_thickness 0.25)
			(keepout
				(tracks allowed)
				(vias not_allowed)
				(pads allowed)
				(copperpour not_allowed)
				(footprints allowed)
			)
			(placement
				(enabled no)
				(sheetname "")
			)
			(fill
				(thermal_gap 0.5)
				(thermal_bridge_width 0.5)
				(island_removal_mode 0)
			)
			(polygon
				(pts
					(xy 374.138952 -42.970958) (xy 373.630952 -42.970958) (xy 373.630952 -42.589958) (xy 374.138952 -42.589958)
				)
			)
		)
		(zone
			(layer "B.Cu")
			(hatch none 0.5)
			(connect_pads
				(clearance 0)
			)
			(min_thickness 0.25)
			(keepout
				(tracks not_allowed)
				(vias allowed)
				(pads allowed)
				(copperpour not_allowed)
				(footprints allowed)
			)
			(placement
				(enabled no)
				(sheetname "")
			)
			(fill
				(thermal_gap 0.5)
				(thermal_bridge_width 0.5)
				(island_removal_mode 0)
			)
			(polygon
				(pts
					(xy 374.138952 -42.589958) (xy 373.630952 -42.589958) (xy 373.630952 -42.970958) (xy 374.138952 -42.970958)
				)
			)
		)
	)
	(footprint ""
		(layer "B.Cu")
		(at 338.7344 -18.16354 -90)
		(property "Reference" "R3T11"
			(at 0 0 90)
			(layer "B.SilkS")
			(hide yes)
			(effects
				(font
					(size 1.27 1.27)
				)
				(justify mirror)
			)
		)
		(property "Value" ""
			(at 0 0 90)
			(layer "B.Fab")
			(effects
				(font
					(size 1.27 1.27)
				)
				(justify mirror)
			)
		)
		(duplicate_pad_numbers_are_jumpers no)
		(fp_rect
			(start 0.2794 0.9906)
			(end -0.2794 -0.1016)
			(stroke
				(width 0)
				(type default)
			)
			(fill no)
			(layer "B.CrtYd")
		)
		(fp_line
			(start -0.2794 0.9906)
			(end -0.2794 -0.1016)
			(stroke
				(width 0.1)
				(type default)
			)
			(layer "B.Fab")
		)
		(fp_line
			(start 0.2794 0.9906)
			(end -0.2794 0.9906)
			(stroke
				(width 0.1)
				(type default)
			)
			(layer "B.Fab")
		)
		(fp_line
			(start -0.2794 -0.1016)
			(end 0.2794 -0.1016)
			(stroke
				(width 0.1)
				(type default)
			)
			(layer "B.Fab")
		)
		(fp_line
			(start 0.2794 -0.1016)
			(end 0.2794 0.9906)
			(stroke
				(width 0.1)
				(type default)
			)
			(layer "B.Fab")
		)
		(pad "1" smd rect
			(at 0 0 90)
			(size 0.508 0.508)
			(layers "B.Cu" "B.Mask" "B.Paste")
			(net "PVCCIO_CPU0")
		)
		(pad "2" smd rect
			(at 0 0.889 90)
			(size 0.508 0.508)
			(layers "B.Cu" "B.Mask" "B.Paste")
			(net "SVID_CLK1_CPU0_R")
		)
		(zone
			(layer "B.Cu")
			(hatch none 0.5)
			(connect_pads
				(clearance 0)
			)
			(min_thickness 0.25)
			(keepout
				(tracks allowed)
				(vias not_allowed)
				(pads allowed)
				(copperpour not_allowed)
				(footprints allowed)
			)
			(placement
				(enabled no)
				(sheetname "")
			)
			(fill
				(thermal_gap 0.5)
				(thermal_bridge_width 0.5)
				(island_removal_mode 0)
			)
			(polygon
				(pts
					(xy 338.0994 -17.90954) (xy 338.4804 -17.90954) (xy 338.4804 -18.41754) (xy 338.0994 -18.41754)
				)
			)
		)
		(zone
			(layer "B.Cu")
			(hatch none 0.5)
			(connect_pads
				(clearance 0)
			)
			(min_thickness 0.25)
			(keepout
				(tracks not_allowed)
				(vias allowed)
				(pads allowed)
				(copperpour not_allowed)
				(footprints allowed)
			)
			(placement
				(enabled no)
				(sheetname "")
			)
			(fill
				(thermal_gap 0.5)
				(thermal_bridge_width 0.5)
				(island_removal_mode 0)
			)
			(polygon
				(pts
					(xy 338.0994 -17.90954) (xy 338.4804 -17.90954) (xy 338.4804 -18.41754) (xy 338.0994 -18.41754)
				)
			)
		)
	)
	(footprint ""
		(layer "B.Cu")
		(at 489.189014 -140.589 90)
		(property "Reference" "Q1L4"
			(at -2.86131 2.27838 0)
			(unlocked yes)
			(layer "B.SilkS")
			(effects
				(font
					(size 0.7874 0.5842)
					(thickness 0.1524)
				)
				(justify left mirror)
			)
		)
		(property "Value" ""
			(at 0 0 90)
			(layer "B.Fab")
			(effects
				(font
					(size 1.27 1.27)
				)
				(justify mirror)
			)
		)
		(duplicate_pad_numbers_are_jumpers no)
		(fp_circle
			(center 0.848614 -0.6477)
			(end 0.848614 -0.5207)
			(stroke
				(width 0.254)
				(type default)
			)
			(fill no)
			(layer "B.SilkS")
		)
		(fp_poly
			(pts
				(xy -0.21463 -0.450088) (xy -1.56337 -0.450088) (xy -1.56337 1.75006) (xy -0.21463 1.75006)
			)
			(stroke
				(width 0)
				(type default)
			)
			(fill no)
			(layer "B.CrtYd")
		)
		(fp_line
			(start -0.21463 -0.450088)
			(end -1.56337 -0.450088)
			(stroke
				(width 0.1)
				(type default)
			)
			(layer "B.Fab")
		)
		(fp_line
			(start -1.56337 -0.450088)
			(end -1.56337 1.75006)
			(stroke
				(width 0.1)
				(type default)
			)
			(layer "B.Fab")
		)
		(fp_line
			(start -0.21463 1.75006)
			(end -0.21463 -0.450088)
			(stroke
				(width 0.1)
				(type default)
			)
			(layer "B.Fab")
		)
		(fp_line
			(start -1.56337 1.75006)
			(end -0.21463 1.75006)
			(stroke
				(width 0.1)
				(type default)
			)
			(layer "B.Fab")
		)
		(fp_circle
			(center 0.848614 -0.6477)
			(end 0.848614 -0.5207)
			(stroke
				(width 0.254)
				(type default)
			)
			(fill no)
			(layer "B.Fab")
		)
		(pad "1" smd rect
			(at 0 0 270)
			(size 1.016 0.381)
			(layers "B.Cu" "B.Mask" "B.Paste")
			(net "GND")
		)
		(pad "2" smd rect
			(at 0 0.649986 270)
			(size 1.016 0.381)
			(layers "B.Cu" "B.Mask" "B.Paste")
			(net "FM_DB_PRESENT")
		)
		(pad "3" smd rect
			(at 0 1.299972 270)
			(size 1.016 0.381)
			(layers "B.Cu" "B.Mask" "B.Paste")
			(net "TP_FET_Q56_3")
		)
		(pad "4" smd rect
			(at -1.778 1.299972 270)
			(size 1.016 0.381)
			(layers "B.Cu" "B.Mask" "B.Paste")
			(net "TP_FET_Q56_4")
		)
		(pad "5" smd rect
			(at -1.778 0.649986 270)
			(size 1.016 0.381)
			(layers "B.Cu" "B.Mask" "B.Paste")
			(net "TP_FET_Q56_4")
		)
		(pad "6" smd rect
			(at -1.778 0 270)
			(size 1.016 0.381)
			(layers "B.Cu" "B.Mask" "B.Paste")
			(net "FM_POST_CARD_PRES_BMC_N")
		)
	)
)
